# BASEBOARD_FAB2 (Tioga Pass) — schematic netlist excerpt (pin names and nets, part order shuffled) for the footprints in the layout excerpt that follows; sources: Cadence DE-HDL packaged netlist, KiCad conversion of Wiwynn_Tioga_Pass_MB.brd

R4U3  RES  4.75K 1% CHIP  pkg 0402  page 94 : A = PVPP_ABC ; B = FM_DIMM_EVENT_FET
R1U34  RES  33.2 1% CHIP  pkg 0402  page 152 : A = H_CPU1_MEMKLM_MEMHOT_LVT3_K_N ; B = H_CPU1_MEMKLM_MEMHOT_LVT3_N
R2U19  RES  0.0 5% CHIP  pkg 0402  page 107 : A = P3E_CPU0_PE1_SS_RXN<2> ; B = P3E_CPU0_PE1_SS_R_RXN<2>

(kicad_pcb
	(version 20260206)
	(generator "pcbnew")
	(generator_version "10.0")
	(general
		(thickness 1.6)
		(legacy_teardrops no)
	)
	(paper "A4")
	(title_block
		(title "Wiwynn_Tioga_Pass_MB.brd")
		(comment 1 "Tioga Pass / footprints 4050-4052 of 4770")
	)
	(layers
		(0 "F.Cu" signal "TOP")
		(4 "In1.Cu" signal "L2GND")
		(6 "In2.Cu" signal "L3")
		(8 "In3.Cu" signal "L4GND")
		(10 "In4.Cu" signal "L5")
		(12 "In5.Cu" signal "L6GND")
		(14 "In6.Cu" signal "L7VCC")
		(16 "In7.Cu" signal "L8VCC")
		(18 "In8.Cu" signal "L9GND")
		(20 "In9.Cu" signal "L10")
		(22 "In10.Cu" signal "L11GND")
		(24 "In11.Cu" signal "L12")
		(26 "In12.Cu" signal "L13GND")
		(2 "B.Cu" signal "BOTTOM")
		(9 "F.Adhes" user "F.Adhesive")
		(11 "B.Adhes" user "B.Adhesive")
		(13 "F.Paste" user "Package Geometry/Pastemask Top")
		(15 "B.Paste" user "Package Geometry/Pastemask Bottom")
		(5 "F.SilkS" user "Ref Des/Silkscreen Top")
		(7 "B.SilkS" user "Ref Des/Silkscreen Bottom")
		(1 "F.Mask" user "Board Geometry/Soldermask Top")
		(3 "B.Mask" user "Board Geometry/Soldermask Bottom")
		(17 "Dwgs.User" user "User.Drawings")
		(19 "Cmts.User" user "User.Comments")
		(21 "Eco1.User" user "User.Eco1")
		(23 "Eco2.User" user "User.Eco2")
		(25 "Edge.Cuts" user "Board Geometry/Outline")
		(27 "Margin" user)
		(31 "F.CrtYd" user "Package Geometry/Place Bound Top")
		(29 "B.CrtYd" user "Package Geometry/Place Bound Bottom")
		(35 "F.Fab" user "Ref Des/Assembly Top")
		(33 "B.Fab" user "Ref Des/Assembly Bottom")
	)
	(footprint ""
		(layer "B.Cu")
		(at 329.438 -8.382)
		(property "Reference" "R4U3"
			(at 0 0 0)
			(layer "B.SilkS")
			(hide yes)
			(effects
				(font
					(size 1.27 1.27)
				)
				(justify mirror)
			)
		)
		(property "Value" ""
			(at 0 0 0)
			(layer "B.Fab")
			(effects
				(font
					(size 1.27 1.27)
				)
				(justify mirror)
			)
		)
		(duplicate_pad_numbers_are_jumpers no)
		(fp_poly
			(pts
				(xy 0.2794 -0.1016) (xy -0.2794 -0.1016) (xy -0.2794 0.9906) (xy 0.2794 0.9906)
			)
			(stroke
				(width 0)
				(type default)
			)
			(fill no)
			(layer "B.CrtYd")
		)
		(fp_line
			(start -0.2794 -0.1016)
			(end 0.2794 -0.1016)
			(stroke
				(width 0.1)
				(type default)
			)
			(layer "B.Fab")
		)
		(fp_line
			(start -0.2794 0.9906)
			(end -0.2794 -0.1016)
			(stroke
				(width 0.1)
				(type default)
			)
			(layer "B.Fab")
		)
		(fp_line
			(start 0.2794 -0.1016)
			(end 0.2794 0.9906)
			(stroke
				(width 0.1)
				(type default)
			)
			(layer "B.Fab")
		)
		(fp_line
			(start 0.2794 0.9906)
			(end -0.2794 0.9906)
			(stroke
				(width 0.1)
				(type default)
			)
			(layer "B.Fab")
		)
		(pad "1" smd rect
			(at 0 0 180)
			(size 0.508 0.508)
			(layers "B.Cu" "B.Mask" "B.Paste")
			(net "PVPP_ABC")
		)
		(pad "2" smd rect
			(at 0 0.889 180)
			(size 0.508 0.508)
			(layers "B.Cu" "B.Mask" "B.Paste")
			(net "FM_DIMM_EVENT_FET")
		)
		(zone
			(layer "B.Cu")
			(hatch none 0.5)
			(connect_pads
				(clearance 0)
			)
			(min_thickness 0.25)
			(keepout
				(tracks allowed)
				(vias not_allowed)
				(pads allowed)
				(copperpour not_allowed)
				(footprints allowed)
			)
			(placement
				(enabled no)
				(sheetname "")
			)
			(fill
				(thermal_gap 0.5)
				(thermal_bridge_width 0.5)
				(island_removal_mode 0)
			)
			(polygon
				(pts
					(xy 329.692 -8.128) (xy 329.184 -8.128) (xy 329.184 -7.747) (xy 329.692 -7.747)
				)
			)
		)
		(zone
			(layer "B.Cu")
			(hatch none 0.5)
			(connect_pads
				(clearance 0)
			)
			(min_thickness 0.25)
			(keepout
				(tracks not_allowed)
				(vias allowed)
				(pads allowed)
				(copperpour not_allowed)
				(footprints allowed)
			)
			(placement
				(enabled no)
				(sheetname "")
			)
			(fill
				(thermal_gap 0.5)
				(thermal_bridge_width 0.5)
				(island_removal_mode 0)
			)
			(polygon
				(pts
					(xy 329.692 -7.747) (xy 329.184 -7.747) (xy 329.184 -8.128) (xy 329.692 -8.128)
				)
			)
		)
	)
	(footprint ""
		(layer "B.Cu")
		(at 434.6575 -18.288 -90)
		(property "Reference" "R1U34"
			(at 0 0 90)
			(layer "B.SilkS")
			(hide yes)
			(effects
				(font
					(size 1.27 1.27)
				)
				(justify mirror)
			)
		)
		(property "Value" ""
			(at 0 0 90)
			(layer "B.Fab")
			(effects
				(font
					(size 1.27 1.27)
				)
				(justify mirror)
			)
		)
		(duplicate_pad_numbers_are_jumpers no)
		(fp_poly
			(pts
				(xy 0.2794 -0.1016) (xy -0.2794 -0.1016) (xy -0.2794 0.9906) (xy 0.2794 0.9906)
			)
			(stroke
				(width 0)
				(type default)
			)
			(fill no)
			(layer "B.CrtYd")
		)
		(fp_line
			(start -0.2794 0.9906)
			(end -0.2794 -0.1016)
			(stroke
				(width 0.1)
				(type default)
			)
			(layer "B.Fab")
		)
		(fp_line
			(start 0.2794 0.9906)
			(end -0.2794 0.9906)
			(stroke
				(width 0.1)
				(type default)
			)
			(layer "B.Fab")
		)
		(fp_line
			(start -0.2794 -0.1016)
			(end 0.2794 -0.1016)
			(stroke
				(width 0.1)
				(type default)
			)
			(layer "B.Fab")
		)
		(fp_line
			(start 0.2794 -0.1016)
			(end 0.2794 0.9906)
			(stroke
				(width 0.1)
				(type default)
			)
			(layer "B.Fab")
		)
		(pad "1" smd rect
			(at 0 0 90)
			(size 0.508 0.508)
			(layers "B.Cu" "B.Mask" "B.Paste")
			(net "H_CPU1_MEMKLM_MEMHOT_LVT3_K_N")
		)
		(pad "2" smd rect
			(at 0 0.889 90)
			(size 0.508 0.508)
			(layers "B.Cu" "B.Mask" "B.Paste")
			(net "H_CPU1_MEMKLM_MEMHOT_LVT3_N")
		)
		(zone
			(layer "B.Cu")
			(hatch none 0.5)
			(connect_pads
				(clearance 0)
			)
			(min_thickness 0.25)
			(keepout
				(tracks not_allowed)
				(vias allowed)
				(pads allowed)
				(copperpour not_allowed)
				(footprints allowed)
			)
			(placement
				(enabled no)
				(sheetname "")
			)
			(fill
				(thermal_gap 0.5)
				(thermal_bridge_width 0.5)
				(island_removal_mode 0)
			)
			(polygon
				(pts
					(xy 434.0225 -18.034) (xy 434.0225 -18.542) (xy 434.4035 -18.542) (xy 434.4035 -18.034)
				)
			)
		)
		(zone
			(layer "B.Cu")
			(hatch none 0.5)
			(connect_pads
				(clearance 0)
			)
			(min_thickness 0.25)
			(keepout
				(tracks allowed)
				(vias not_allowed)
				(pads allowed)
				(copperpour not_allowed)
				(footprints allowed)
			)
			(placement
				(enabled no)
				(sheetname "")
			)
			(fill
				(thermal_gap 0.5)
				(thermal_bridge_width 0.5)
				(island_removal_mode 0)
			)
			(polygon
				(pts
					(xy 434.4035 -18.034) (xy 434.4035 -18.542) (xy 434.0225 -18.542) (xy 434.0225 -18.034)
				)
			)
		)
	)
	(footprint ""
		(layer "B.Cu")
		(at 340.331806 -60.368434)
		(property "Reference" "R2U19"
			(at 0 0 0)
			(layer "B.SilkS")
			(hide yes)
			(effects
				(font
					(size 1.27 1.27)
				)
				(justify mirror)
			)
		)
		(property "Value" ""
			(at 0 0 0)
			(layer "B.Fab")
			(effects
				(font
					(size 1.27 1.27)
				)
				(justify mirror)
			)
		)
		(duplicate_pad_numbers_are_jumpers no)
		(fp_poly
			(pts
				(xy 0.2794 -0.1016) (xy -0.2794 -0.1016) (xy -0.2794 0.9906) (xy 0.2794 0.9906)
			)
			(stroke
				(width 0)
				(type default)
			)
			(fill no)
			(layer "B.CrtYd")
		)
		(fp_line
			(start -0.2794 -0.1016)
			(end 0.2794 -0.1016)
			(stroke
				(width 0.1)
				(type default)
			)
			(layer "B.Fab")
		)
		(fp_line
			(start -0.2794 0.9906)
			(end -0.2794 -0.1016)
			(stroke
				(width 0.1)
				(type default)
			)
			(layer "B.Fab")
		)
		(fp_line
			(start 0.2794 -0.1016)
			(end 0.2794 0.9906)
			(stroke
				(width 0.1)
				(type default)
			)
			(layer "B.Fab")
		)
		(fp_line
			(start 0.2794 0.9906)
			(end -0.2794 0.9906)
			(stroke
				(width 0.1)
				(type default)
			)
			(layer "B.Fab")
		)
		(pad "1" smd rect
			(at 0 0 180)
			(size 0.508 0.508)
			(layers "B.Cu" "B.Mask" "B.Paste")
			(net "P3E_CPU0_PE1_SS_RXN<2>")
		)
		(pad "2" smd rect
			(at 0 0.889 180)
			(size 0.508 0.508)
			(layers "B.Cu" "B.Mask" "B.Paste")
			(net "P3E_CPU0_PE1_SS_R_RXN<2>")
		)
		(zone
			(layer "B.Cu")
			(hatch none 0.5)
			(connect_pads
				(clearance 0)
			)
			(min_thickness 0.25)
			(keepout
				(tracks allowed)
				(vias not_allowed)
				(pads allowed)
				(copperpour not_allowed)
				(footprints allowed)
			)
			(placement
				(enabled no)
				(sheetname "")
			)
			(fill
				(thermal_gap 0.5)
				(thermal_bridge_width 0.5)
				(island_removal_mode 0)
			)
			(polygon
				(pts
					(xy 340.585806 -60.114434) (xy 340.077806 -60.114434) (xy 340.077806 -59.733434) (xy 340.585806 -59.733434)
				)
			)
		)
		(zone
			(layer "B.Cu")
			(hatch none 0.5)
			(connect_pads
				(clearance 0)
			)
			(min_thickness 0.25)
			(keepout
				(tracks not_allowed)
				(vias allowed)
				(pads allowed)
				(copperpour not_allowed)
				(footprints allowed)
			)
			(placement
				(enabled no)
				(sheetname "")
			)
			(fill
				(thermal_gap 0.5)
				(thermal_bridge_width 0.5)
				(island_removal_mode 0)
			)
			(polygon
				(pts
					(xy 340.585806 -59.733434) (xy 340.077806 -59.733434) (xy 340.077806 -60.114434) (xy 340.585806 -60.114434)
				)
			)
		)
	)
)
